#ISCELL
  pure_quanta quanta_title_block_c *
  *
#ISCELL
  standard offpage *
  page242_i1
#ISCELL
  logical_power universal_gnd *
  page242_i10
#CELL
  pure_quanta q_led *
  page242_i11
#CELL
  pure_quanta q_res *
  page242_i12
#CELL
  pure_quanta q_led *
  page242_i13
#CELL
  pure_quanta q_res *
  page242_i14
#CELL
  pure_quanta q_res *
  page242_i15
#ISCELL
  standard offpage *
  page242_i16
#CELL
  pure_quanta mosfet_nch_dual *
  page242_i17
#CELL
  pure_quanta q_led *
  page242_i18
#CELL
  pure_quanta q_res *
  page242_i19
#ISCELL
  standard offpage *
  page242_i2
#ISCELL
  logical_power universal_power *
  page242_i20
#ISCELL
  logical_power universal_power *
  page242_i23
#ISCELL
  standard offpage *
  page242_i24
#ISCELL
  logical_power universal_power *
  page242_i25
#CELL
  pure_quanta mosfet_nch_dual *
  page242_i26
#ISCELL
  logical_power universal_gnd *
  page242_i28
#CELL
  pure_quanta mosfet_nch_dual *
  page242_i3
#ISCELL
  logical_power universal_gnd *
  page242_i30
#CELL
  pure_quanta q_led *
  page242_i31
#ISCELL
  logical_power universal_power *
  page242_i32
#ISCELL
  standard offpage *
  page242_i33
#CELL
  pure_quanta mosfet_nch_dual *
  page242_i34
#CELL
  pure_quanta q_led *
  page242_i35
#CELL
  pure_quanta q_res *
  page242_i37
#ISCELL
  logical_power universal_power *
  page242_i39
#ISCELL
  logical_power universal_gnd *
  page242_i4
#ISCELL
  logical_power universal_power *
  page242_i40
#CELL
  pure_quanta q_res *
  page242_i41
#CELL
  pure_quanta q_led *
  page242_i42
#ISCELL
  logical_power universal_gnd *
  page242_i49
#ISCELL
  logical_power universal_gnd *
  page242_i5
#ISCELL
  logical_power universal_power *
  page242_i51
#CELL
  pure_quanta q_led *
  page242_i52
#CELL
  pure_quanta q_led *
  page242_i53
#ISCELL
  logical_power universal_power *
  page242_i54
#ISCELL
  logical_power universal_gnd *
  page242_i56
#ISCELL
  logical_power universal_gnd *
  page242_i57
#ISCELL
  logical_power universal_power *
  page242_i59
#CELL
  pure_quanta mosfet_nch_dual *
  page242_i6
#CELL
  pure_quanta q_led *
  page242_i60
#CELL
  pure_quanta q_res *
  page242_i61
#CELL
  pure_quanta q_res *
  page242_i62
#CELL
  pure_quanta q_res *
  page242_i64
#ISCELL
  standard offpage *
  page242_i7
#CELL
  pure_quanta mosfet_nch_dual *
  page242_i8
#ISCELL
  logical_power universal_gnd *
  page242_i9
